# SCM (Grand Teton) — schematic netlist excerpt (pin names and nets, part order shuffled) for the footprints in the layout excerpt that follows; sources: Cadence DE-HDL packaged netlist, KiCad conversion of 12092022_DA0F0TMDCD0_F0T_Management_Board_D_brd_V3_OCP.brd

R400  Q_RES  4.7K 1% EMPTY  pkg 0402LF  page 12 : A = P3V3_AUX ; B = FM_THERMTRIP_DLY_LVC1_R_N
R311  Q_RES  33.2 1% CHIP  pkg 0402LF  page 12 : A = ESPI_HOST_LPC_BMC_LFRAME_N ; B = ESPI_HOST_LPC_BMC_LFRAME_N_R

(kicad_pcb
	(version 20260206)
	(generator "pcbnew")
	(generator_version "10.0")
	(general
		(thickness 1.6)
		(legacy_teardrops no)
	)
	(paper "A4")
	(title_block
		(title "12092022_DA0F0TMDCD0_F0T_Management_Board_D_brd_V3_OCP.brd")
		(comment 1 "Grand Teton / footprints 394-395 of 1440")
	)
	(layers
		(0 "F.Cu" signal "TOP")
		(4 "In1.Cu" signal "GND")
		(6 "In2.Cu" signal "IN1")
		(8 "In3.Cu" signal "GND1")
		(10 "In4.Cu" signal "IN2")
		(12 "In5.Cu" signal "VCC")
		(14 "In6.Cu" signal "VCC1")
		(16 "In7.Cu" signal "IN3")
		(18 "In8.Cu" signal "GND2")
		(20 "In9.Cu" signal "IN4")
		(22 "In10.Cu" signal "GND3")
		(2 "B.Cu" signal "BOTTOM")
		(9 "F.Adhes" user "F.Adhesive")
		(11 "B.Adhes" user "B.Adhesive")
		(13 "F.Paste" user "Package Geometry/Pastemask Top")
		(15 "B.Paste" user "Package Geometry/Pastemask Bottom")
		(5 "F.SilkS" user "Ref Des/Silkscreen Top")
		(7 "B.SilkS" user "Ref Des/Silkscreen Bottom")
		(1 "F.Mask" user "Board Geometry/Soldermask Top")
		(3 "B.Mask" user "Board Geometry/Soldermask Bottom")
		(17 "Dwgs.User" user "User.Drawings")
		(19 "Cmts.User" user "User.Comments")
		(21 "Eco1.User" user "User.Eco1")
		(23 "Eco2.User" user "User.Eco2")
		(25 "Edge.Cuts" user "Board Geometry/Outline")
		(27 "Margin" user)
		(31 "F.CrtYd" user "Package Geometry/Place Bound Top")
		(29 "B.CrtYd" user "Package Geometry/Place Bound Bottom")
		(35 "F.Fab" user "Ref Des/Assembly Top")
		(33 "B.Fab" user "Ref Des/Assembly Bottom")
	)
	(footprint ""
		(layer "F.Cu")
		(at 65.5066 -108.0008 -90)
		(property "Reference" "R311"
			(at 0 0 270)
			(layer "F.SilkS")
			(hide yes)
			(effects
				(font
					(size 1.27 1.27)
				)
			)
		)
		(property "Value" ""
			(at 0 0 270)
			(layer "F.Fab")
			(effects
				(font
					(size 1.27 1.27)
				)
			)
		)
		(duplicate_pad_numbers_are_jumpers no)
		(fp_line
			(start -0.7874 0.4064)
			(end -0.7874 -0.4064)
			(stroke
				(width 0.1524)
				(type default)
			)
			(layer "F.SilkS")
		)
		(fp_line
			(start 0.7874 0.4064)
			(end -0.7874 0.4064)
			(stroke
				(width 0.1524)
				(type default)
			)
			(layer "F.SilkS")
		)
		(fp_line
			(start -0.7874 -0.4064)
			(end 0.7874 -0.4064)
			(stroke
				(width 0.1524)
				(type default)
			)
			(layer "F.SilkS")
		)
		(fp_line
			(start 0.7874 -0.4064)
			(end 0.7874 0.4064)
			(stroke
				(width 0.1524)
				(type default)
			)
			(layer "F.SilkS")
		)
		(fp_line
			(start -0.67945 0.3048)
			(end -0.67945 -0.305054)
			(stroke
				(width 0.1)
				(type default)
			)
			(layer "F.Fab")
		)
		(fp_line
			(start -0.12065 0.3048)
			(end -0.67945 0.3048)
			(stroke
				(width 0.1)
				(type default)
			)
			(layer "F.Fab")
		)
		(fp_line
			(start 0.120396 0.3048)
			(end 0.120396 0.2794)
			(stroke
				(width 0.1)
				(type default)
			)
			(layer "F.Fab")
		)
		(fp_line
			(start 0.67945 0.3048)
			(end 0.120396 0.3048)
			(stroke
				(width 0.1)
				(type default)
			)
			(layer "F.Fab")
		)
		(fp_line
			(start -0.12065 0.2794)
			(end -0.12065 0.3048)
			(stroke
				(width 0.1)
				(type default)
			)
			(layer "F.Fab")
		)
		(fp_line
			(start 0.120396 0.2794)
			(end -0.12065 0.2794)
			(stroke
				(width 0.1)
				(type default)
			)
			(layer "F.Fab")
		)
		(fp_line
			(start -0.12065 -0.2794)
			(end 0.12065 -0.2794)
			(stroke
				(width 0.1)
				(type default)
			)
			(layer "F.Fab")
		)
		(fp_line
			(start 0.12065 -0.2794)
			(end 0.12065 -0.3048)
			(stroke
				(width 0.1)
				(type default)
			)
			(layer "F.Fab")
		)
		(fp_line
			(start 0.12065 -0.3048)
			(end 0.67945 -0.3048)
			(stroke
				(width 0.1)
				(type default)
			)
			(layer "F.Fab")
		)
		(fp_line
			(start 0.67945 -0.3048)
			(end 0.67945 0.3048)
			(stroke
				(width 0.1)
				(type default)
			)
			(layer "F.Fab")
		)
		(fp_line
			(start -0.67945 -0.305054)
			(end -0.12065 -0.305054)
			(stroke
				(width 0.1)
				(type default)
			)
			(layer "F.Fab")
		)
		(fp_line
			(start -0.12065 -0.305054)
			(end -0.12065 -0.2794)
			(stroke
				(width 0.1)
				(type default)
			)
			(layer "F.Fab")
		)
		(pad "1" smd circle
			(at -0.40005 0 270)
			(size 0 0)
			(layers "F.Cu" "F.Mask" "F.Paste")
			(net "ESPI_HOST_LPC_BMC_LFRAME_N")
		)
		(pad "2" smd circle
			(at 0.40005 0 270)
			(size 0 0)
			(layers "F.Cu" "F.Mask" "F.Paste")
			(net "ESPI_HOST_LPC_BMC_LFRAME_N_R")
		)
	)
	(footprint ""
		(layer "F.Cu")
		(at 39.5732 -49.7078)
		(property "Reference" "R400"
			(at 0 0 0)
			(layer "F.SilkS")
			(hide yes)
			(effects
				(font
					(size 1.27 1.27)
				)
			)
		)
		(property "Value" ""
			(at 0 0 0)
			(layer "F.Fab")
			(effects
				(font
					(size 1.27 1.27)
				)
			)
		)
		(duplicate_pad_numbers_are_jumpers no)
		(fp_line
			(start -0.7874 -0.4064)
			(end 0.7874 -0.4064)
			(stroke
				(width 0.1524)
				(type default)
			)
			(layer "F.SilkS")
		)
		(fp_line
			(start -0.7874 0.4064)
			(end -0.7874 -0.4064)
			(stroke
				(width 0.1524)
				(type default)
			)
			(layer "F.SilkS")
		)
		(fp_line
			(start 0.7874 -0.4064)
			(end 0.7874 0.4064)
			(stroke
				(width 0.1524)
				(type default)
			)
			(layer "F.SilkS")
		)
		(fp_line
			(start 0.7874 0.4064)
			(end -0.7874 0.4064)
			(stroke
				(width 0.1524)
				(type default)
			)
			(layer "F.SilkS")
		)
		(fp_line
			(start -0.67945 -0.305054)
			(end -0.12065 -0.305054)
			(stroke
				(width 0.1)
				(type default)
			)
			(layer "F.Fab")
		)
		(fp_line
			(start -0.67945 0.3048)
			(end -0.67945 -0.305054)
			(stroke
				(width 0.1)
				(type default)
			)
			(layer "F.Fab")
		)
		(fp_line
			(start -0.12065 -0.305054)
			(end -0.12065 -0.2794)
			(stroke
				(width 0.1)
				(type default)
			)
			(layer "F.Fab")
		)
		(fp_line
			(start -0.12065 -0.2794)
			(end 0.12065 -0.2794)
			(stroke
				(width 0.1)
				(type default)
			)
			(layer "F.Fab")
		)
		(fp_line
			(start -0.12065 0.2794)
			(end -0.12065 0.3048)
			(stroke
				(width 0.1)
				(type default)
			)
			(layer "F.Fab")
		)
		(fp_line
			(start -0.12065 0.3048)
			(end -0.67945 0.3048)
			(stroke
				(width 0.1)
				(type default)
			)
			(layer "F.Fab")
		)
		(fp_line
			(start 0.120396 0.2794)
			(end -0.12065 0.2794)
			(stroke
				(width 0.1)
				(type default)
			)
			(layer "F.Fab")
		)
		(fp_line
			(start 0.120396 0.3048)
			(end 0.120396 0.2794)
			(stroke
				(width 0.1)
				(type default)
			)
			(layer "F.Fab")
		)
		(fp_line
			(start 0.12065 -0.3048)
			(end 0.67945 -0.3048)
			(stroke
				(width 0.1)
				(type default)
			)
			(layer "F.Fab")
		)
		(fp_line
			(start 0.12065 -0.2794)
			(end 0.12065 -0.3048)
			(stroke
				(width 0.1)
				(type default)
			)
			(layer "F.Fab")
		)
		(fp_line
			(start 0.67945 -0.3048)
			(end 0.67945 0.3048)
			(stroke
				(width 0.1)
				(type default)
			)
			(layer "F.Fab")
		)
		(fp_line
			(start 0.67945 0.3048)
			(end 0.120396 0.3048)
			(stroke
				(width 0.1)
				(type default)
			)
			(layer "F.Fab")
		)
		(pad "1" smd circle
			(at -0.40005 0)
			(size 0 0)
			(layers "F.Cu" "F.Mask" "F.Paste")
			(net "P3V3_AUX")
		)
		(pad "2" smd circle
			(at 0.40005 0)
			(size 0 0)
			(layers "F.Cu" "F.Mask" "F.Paste")
			(net "FM_THERMTRIP_DLY_LVC1_R_N")
		)
	)
)
